(kicad_pcb
	(version 20241229)
	(generator "pcbnew")
	(generator_version "9.0")
	(general
		(thickness 1.599998)
		(legacy_teardrops no)
	)
	(paper "A4")
	(title_block
		(date "2023-02-12")
		(rev "1.1.5")
		(comment 9 "footprints 463-469 of 473")
	)
	(layers
		(0 "F.Cu" signal)
		(4 "In1.Cu" power "In1.GND")
		(6 "In2.Cu" signal)
		(8 "In3.Cu" power "In3.GND")
		(10 "In4.Cu" power "In4.VCC")
		(12 "In5.Cu" signal)
		(14 "In6.Cu" power "In6.VCC")
		(2 "B.Cu" signal)
		(9 "F.Adhes" user "F.Adhesive")
		(11 "B.Adhes" user "B.Adhesive")
		(13 "F.Paste" user)
		(15 "B.Paste" user)
		(5 "F.SilkS" user "F.Silkscreen")
		(7 "B.SilkS" user "B.Silkscreen")
		(1 "F.Mask" user)
		(3 "B.Mask" user)
		(17 "Dwgs.User" user "User.Drawings")
		(19 "Cmts.User" user "User.Comments")
		(21 "Eco1.User" user "User.Eco1")
		(23 "Eco2.User" user "User.Eco2")
		(25 "Edge.Cuts" user)
		(27 "Margin" user)
		(31 "F.CrtYd" user "F.Courtyard")
		(29 "B.CrtYd" user "B.Courtyard")
		(35 "F.Fab" user)
		(33 "B.Fab" user)
	)
	(footprint "antmicro-footprints:C_0402_1005Metric"
		(layer "B.Cu")
		(at 136.3 79.7)
		(descr "Capacitor SMD 0402")
		(tags "capacitor SMD 0402")
		(property "Reference" "C144"
			(at 1.4 1.3 180)
			(layer "B.SilkS")
			(effects
				(font
					(size 0.7 0.7)
					(thickness 0.15)
				)
				(justify left bottom mirror)
			)
		)
		(property "Value" "C_100n_6V3_0402"
			(at 0 -1.4 180)
			(layer "B.Fab")
			(effects
				(font
					(size 0.7 0.7)
					(thickness 0.15)
				)
				(justify left bottom mirror)
			)
		)
		(property "Description" " "
			(at 0 0 0)
			(layer "F.Fab")
			(hide yes)
			(effects
				(font
					(size 1.27 1.27)
					(thickness 0.15)
				)
			)
		)
		(property "Author" "Antmicro"
			(at 0 0 0)
			(layer "B.Fab")
			(hide yes)
			(effects
				(font
					(size 1 1)
					(thickness 0.15)
				)
				(justify mirror)
			)
		)
		(property "Dielectric" ""
			(at 0 0 0)
			(layer "B.Fab")
			(hide yes)
			(effects
				(font
					(size 1 1)
					(thickness 0.15)
				)
				(justify mirror)
			)
		)
		(property "License" "Apache-2.0"
			(at 0 0 0)
			(layer "B.Fab")
			(hide yes)
			(effects
				(font
					(size 1 1)
					(thickness 0.15)
				)
				(justify mirror)
			)
		)
		(property "MPN" "0402X104K6R3CT"
			(at 0 0 0)
			(layer "B.Fab")
			(hide yes)
			(effects
				(font
					(size 1 1)
					(thickness 0.15)
				)
				(justify mirror)
			)
		)
		(property "Manufacturer" "Walsin"
			(at 0 0 0)
			(layer "B.Fab")
			(hide yes)
			(effects
				(font
					(size 1 1)
					(thickness 0.15)
				)
				(justify mirror)
			)
		)
		(property "Val" "100n"
			(at 0 0 0)
			(layer "B.Fab")
			(hide yes)
			(effects
				(font
					(size 1 1)
					(thickness 0.15)
				)
				(justify mirror)
			)
		)
		(property "Voltage" ""
			(at 0 0 0)
			(layer "B.Fab")
			(hide yes)
			(effects
				(font
					(size 1 1)
					(thickness 0.15)
				)
				(justify mirror)
			)
		)
		(sheetname "Supply")
		(sheetfile "supply.kicad_sch")
		(attr exclude_from_pos_files exclude_from_bom dnp)
		(fp_rect
			(start -0.94 0.47)
			(end 0.94 -0.47)
			(stroke
				(width 0.05)
				(type solid)
			)
			(fill no)
			(layer "B.CrtYd")
		)
		(fp_rect
			(start -0.499 0.249)
			(end 0.499 -0.249)
			(stroke
				(width 0.15)
				(type solid)
			)
			(fill no)
			(layer "B.Fab")
		)
		(pad "1" smd roundrect
			(at -0.484 0)
			(size 0.59 0.64)
			(layers "B.Cu" "B.Mask" "B.Paste")
			(roundrect_rratio 0.25)
			(net 459 "3V3_SYS")
			(pintype "passive")
		)
		(pad "2" smd roundrect
			(at 0.484 0)
			(size 0.59 0.64)
			(layers "B.Cu" "B.Mask" "B.Paste")
			(roundrect_rratio 0.25)
			(net 5 "GND")
			(pintype "passive")
		)
	)
	(footprint "antmicro-footprints:R_0805_2012Metric"
		(layer "B.Cu")
		(at 136.4 67.2)
		(property "Reference" "R165"
			(at -1.6 0.4 180)
			(layer "B.SilkS")
			(effects
				(font
					(size 0.7 0.7)
					(thickness 0.15)
				)
				(justify left bottom mirror)
			)
		)
		(property "Value" "R_0R_0805"
			(at 0 -1.8 180)
			(layer "B.Fab")
			(effects
				(font
					(size 0.7 0.7)
					(thickness 0.15)
				)
				(justify left bottom mirror)
			)
		)
		(property "Description" "0R resistor in 0805 package with unspecified tolerance"
			(at 0 0 0)
			(layer "F.Fab")
			(hide yes)
			(effects
				(font
					(size 1.27 1.27)
					(thickness 0.15)
				)
			)
		)
		(property "Author" "Antmicro"
			(at 0 0 0)
			(layer "B.Fab")
			(hide yes)
			(effects
				(font
					(size 1 1)
					(thickness 0.15)
				)
				(justify mirror)
			)
		)
		(property "Current" "2.5A"
			(at 0 0 0)
			(layer "B.Fab")
			(hide yes)
			(effects
				(font
					(size 1 1)
					(thickness 0.15)
				)
				(justify mirror)
			)
		)
		(property "License" "Apache-2.0"
			(at 0 0 0)
			(layer "B.Fab")
			(hide yes)
			(effects
				(font
					(size 1 1)
					(thickness 0.15)
				)
				(justify mirror)
			)
		)
		(property "MPN" "CRCW08050000Z0EA"
			(at 0 0 0)
			(layer "B.Fab")
			(hide yes)
			(effects
				(font
					(size 1 1)
					(thickness 0.15)
				)
				(justify mirror)
			)
		)
		(property "Manufacturer" "Vishay"
			(at 0 0 0)
			(layer "B.Fab")
			(hide yes)
			(effects
				(font
					(size 1 1)
					(thickness 0.15)
				)
				(justify mirror)
			)
		)
		(property "Tolerance" ""
			(at 0 0 0)
			(layer "B.Fab")
			(hide yes)
			(effects
				(font
					(size 1 1)
					(thickness 0.15)
				)
				(justify mirror)
			)
		)
		(property "Val" "0R"
			(at 0 0 0)
			(layer "B.Fab")
			(hide yes)
			(effects
				(font
					(size 1 1)
					(thickness 0.15)
				)
				(justify mirror)
			)
		)
		(sheetname "Supply")
		(sheetfile "supply.kicad_sch")
		(attr smd)
		(fp_line
			(start -0.32 -0.699)
			(end 0.28 -0.699)
			(stroke
				(width 0.15)
				(type solid)
			)
			(layer "B.SilkS")
		)
		(fp_line
			(start -0.3 0.701)
			(end 0.298 0.701)
			(stroke
				(width 0.15)
				(type solid)
			)
			(layer "B.SilkS")
		)
		(fp_rect
			(start -1.75 0.85)
			(end 1.75 -0.85)
			(stroke
				(width 0.05)
				(type solid)
			)
			(fill no)
			(layer "B.CrtYd")
		)
		(fp_line
			(start -0.951 -0.68)
			(end 0.949 -0.68)
			(stroke
				(width 0.15)
				(type solid)
			)
			(layer "B.Fab")
		)
		(fp_line
			(start -0.951 0.677)
			(end -0.951 -0.675)
			(stroke
				(width 0.15)
				(type solid)
			)
			(layer "B.Fab")
		)
		(fp_line
			(start -0.951 0.682)
			(end 0.949 0.682)
			(stroke
				(width 0.15)
				(type solid)
			)
			(layer "B.Fab")
		)
		(fp_line
			(start 0.949 0.677)
			(end 0.949 -0.675)
			(stroke
				(width 0.15)
				(type solid)
			)
			(layer "B.Fab")
		)
		(pad "1" smd roundrect
			(at -1.1 0.001)
			(size 1 1.4)
			(layers "B.Cu" "B.Mask" "B.Paste")
			(roundrect_rratio 0.15)
			(net 460 "1V8_SYS")
			(pintype "passive")
		)
		(pad "2" smd roundrect
			(at 1.1 0.001)
			(size 1 1.4)
			(layers "B.Cu" "B.Mask" "B.Paste")
			(roundrect_rratio 0.15)
			(net 641 "1V8_DDR")
			(pintype "passive")
		)
	)
	(footprint "antmicro-footprints:R_0402_1005Metric"
		(layer "B.Cu")
		(at 134.2 71.3 180)
		(descr "Resistor SMD 0402")
		(tags "resistor SMD 0402")
		(property "Reference" "R163"
			(at 0.7 -0.4 0)
			(layer "B.SilkS")
			(effects
				(font
					(size 0.7 0.7)
					(thickness 0.15)
				)
				(justify left bottom mirror)
			)
		)
		(property "Value" "R_10k_0402"
			(at 0 -1.4 0)
			(layer "B.Fab")
			(effects
				(font
					(size 0.7 0.7)
					(thickness 0.15)
				)
				(justify left bottom mirror)
			)
		)
		(property "Description" "10k resistor in 0402 package with 1% tolerance"
			(at 0 0 180)
			(layer "F.Fab")
			(hide yes)
			(effects
				(font
					(size 1.27 1.27)
					(thickness 0.15)
				)
			)
		)
		(property "Author" "Antmicro"
			(at 268.4 142.6 0)
			(layer "B.Fab")
			(hide yes)
			(effects
				(font
					(size 1 1)
					(thickness 0.15)
				)
				(justify mirror)
			)
		)
		(property "License" "Apache-2.0"
			(at 268.4 142.6 0)
			(layer "B.Fab")
			(hide yes)
			(effects
				(font
					(size 1 1)
					(thickness 0.15)
				)
				(justify mirror)
			)
		)
		(property "MPN" "CR0402-FX-1002GLF"
			(at 268.4 142.6 0)
			(layer "B.Fab")
			(hide yes)
			(effects
				(font
					(size 1 1)
					(thickness 0.15)
				)
				(justify mirror)
			)
		)
		(property "Manufacturer" "Bourns"
			(at 268.4 142.6 0)
			(layer "B.Fab")
			(hide yes)
			(effects
				(font
					(size 1 1)
					(thickness 0.15)
				)
				(justify mirror)
			)
		)
		(property "Tolerance" "1%"
			(at 268.4 142.6 0)
			(layer "B.Fab")
			(hide yes)
			(effects
				(font
					(size 1 1)
					(thickness 0.15)
				)
				(justify mirror)
			)
		)
		(property "Val" "10k"
			(at 268.4 142.6 0)
			(layer "B.Fab")
			(hide yes)
			(effects
				(font
					(size 1 1)
					(thickness 0.15)
				)
				(justify mirror)
			)
		)
		(sheetname "Supply")
		(sheetfile "supply.kicad_sch")
		(attr exclude_from_pos_files exclude_from_bom dnp)
		(fp_rect
			(start -0.93 0.47)
			(end 0.93 -0.47)
			(stroke
				(width 0.05)
				(type solid)
			)
			(fill no)
			(layer "B.CrtYd")
		)
		(fp_rect
			(start -0.5 0.25)
			(end 0.5 -0.25)
			(stroke
				(width 0.15)
				(type solid)
			)
			(fill no)
			(layer "B.Fab")
		)
		(pad "1" smd roundrect
			(at -0.485 0 180)
			(size 0.59 0.64)
			(layers "B.Cu" "B.Mask" "B.Paste")
			(roundrect_rratio 0.25)
			(net 459 "3V3_SYS")
			(pintype "passive")
		)
		(pad "2" smd roundrect
			(at 0.485 0 180)
			(size 0.59 0.64)
			(layers "B.Cu" "B.Mask" "B.Paste")
			(roundrect_rratio 0.25)
			(net 264 "Net-(U16-ON)")
			(pintype "passive")
		)
	)
	(footprint "antmicro-footprints:C_0402_1005Metric"
		(layer "B.Cu")
		(at 137.9 79.2 -90)
		(descr "Capacitor SMD 0402")
		(tags "capacitor SMD 0402")
		(property "Reference" "C146"
			(at -1.4 -1.3 90)
			(layer "B.SilkS")
			(effects
				(font
					(size 0.7 0.7)
					(thickness 0.15)
				)
				(justify left bottom mirror)
			)
		)
		(property "Value" "C_1n8_0402"
			(at 0 -1.4 90)
			(layer "B.Fab")
			(effects
				(font
					(size 0.7 0.7)
					(thickness 0.15)
				)
				(justify left bottom mirror)
			)
		)
		(property "Description" " "
			(at 0 0 270)
			(layer "F.Fab")
			(hide yes)
			(effects
				(font
					(size 1.27 1.27)
					(thickness 0.15)
				)
			)
		)
		(property "Author" "Antmicro"
			(at 58.7 217.1 0)
			(layer "B.Fab")
			(hide yes)
			(effects
				(font
					(size 1 1)
					(thickness 0.15)
				)
				(justify mirror)
			)
		)
		(property "Dielectric" ""
			(at 58.7 217.1 0)
			(layer "B.Fab")
			(hide yes)
			(effects
				(font
					(size 1 1)
					(thickness 0.15)
				)
				(justify mirror)
			)
		)
		(property "License" "Apache-2.0"
			(at 58.7 217.1 0)
			(layer "B.Fab")
			(hide yes)
			(effects
				(font
					(size 1 1)
					(thickness 0.15)
				)
				(justify mirror)
			)
		)
		(property "MPN" "0402B182K500CT"
			(at 58.7 217.1 0)
			(layer "B.Fab")
			(hide yes)
			(effects
				(font
					(size 1 1)
					(thickness 0.15)
				)
				(justify mirror)
			)
		)
		(property "Manufacturer" "Walsin"
			(at 58.7 217.1 0)
			(layer "B.Fab")
			(hide yes)
			(effects
				(font
					(size 1 1)
					(thickness 0.15)
				)
				(justify mirror)
			)
		)
		(property "Val" "1n8"
			(at 58.7 217.1 0)
			(layer "B.Fab")
			(hide yes)
			(effects
				(font
					(size 1 1)
					(thickness 0.15)
				)
				(justify mirror)
			)
		)
		(property "Voltage" ""
			(at 58.7 217.1 0)
			(layer "B.Fab")
			(hide yes)
			(effects
				(font
					(size 1 1)
					(thickness 0.15)
				)
				(justify mirror)
			)
		)
		(sheetname "Supply")
		(sheetfile "supply.kicad_sch")
		(attr exclude_from_pos_files exclude_from_bom dnp)
		(fp_rect
			(start -0.94 0.47)
			(end 0.94 -0.47)
			(stroke
				(width 0.05)
				(type solid)
			)
			(fill no)
			(layer "B.CrtYd")
		)
		(fp_rect
			(start -0.499 0.249)
			(end 0.499 -0.249)
			(stroke
				(width 0.15)
				(type solid)
			)
			(fill no)
			(layer "B.Fab")
		)
		(pad "1" smd roundrect
			(at -0.484 0 270)
			(size 0.59 0.64)
			(layers "B.Cu" "B.Mask" "B.Paste")
			(roundrect_rratio 0.25)
			(net 60 "Net-(U15-CAP)")
			(pintype "passive")
		)
		(pad "2" smd roundrect
			(at 0.484 0 270)
			(size 0.59 0.64)
			(layers "B.Cu" "B.Mask" "B.Paste")
			(roundrect_rratio 0.25)
			(net 5 "GND")
			(pintype "passive")
		)
	)
	(footprint "antmicro-footprints:C_0402_1005Metric"
		(layer "B.Cu")
		(at 136.3 71.3)
		(descr "Capacitor SMD 0402")
		(tags "capacitor SMD 0402")
		(property "Reference" "C188"
			(at 1.4 1.3 180)
			(layer "B.SilkS")
			(effects
				(font
					(size 0.7 0.7)
					(thickness 0.15)
				)
				(justify left bottom mirror)
			)
		)
		(property "Value" "C_100n_6V3_0402"
			(at 0 -1.4 180)
			(layer "B.Fab")
			(effects
				(font
					(size 0.7 0.7)
					(thickness 0.15)
				)
				(justify left bottom mirror)
			)
		)
		(property "Description" " "
			(at 0 0 0)
			(layer "F.Fab")
			(hide yes)
			(effects
				(font
					(size 1.27 1.27)
					(thickness 0.15)
				)
			)
		)
		(property "Author" "Antmicro"
			(at 0 0 0)
			(layer "B.Fab")
			(hide yes)
			(effects
				(font
					(size 1 1)
					(thickness 0.15)
				)
				(justify mirror)
			)
		)
		(property "Dielectric" ""
			(at 0 0 0)
			(layer "B.Fab")
			(hide yes)
			(effects
				(font
					(size 1 1)
					(thickness 0.15)
				)
				(justify mirror)
			)
		)
		(property "License" "Apache-2.0"
			(at 0 0 0)
			(layer "B.Fab")
			(hide yes)
			(effects
				(font
					(size 1 1)
					(thickness 0.15)
				)
				(justify mirror)
			)
		)
		(property "MPN" "0402X104K6R3CT"
			(at 0 0 0)
			(layer "B.Fab")
			(hide yes)
			(effects
				(font
					(size 1 1)
					(thickness 0.15)
				)
				(justify mirror)
			)
		)
		(property "Manufacturer" "Walsin"
			(at 0 0 0)
			(layer "B.Fab")
			(hide yes)
			(effects
				(font
					(size 1 1)
					(thickness 0.15)
				)
				(justify mirror)
			)
		)
		(property "Val" "100n"
			(at 0 0 0)
			(layer "B.Fab")
			(hide yes)
			(effects
				(font
					(size 1 1)
					(thickness 0.15)
				)
				(justify mirror)
			)
		)
		(property "Voltage" ""
			(at 0 0 0)
			(layer "B.Fab")
			(hide yes)
			(effects
				(font
					(size 1 1)
					(thickness 0.15)
				)
				(justify mirror)
			)
		)
		(sheetname "Supply")
		(sheetfile "supply.kicad_sch")
		(attr exclude_from_pos_files exclude_from_bom dnp)
		(fp_rect
			(start -0.94 0.47)
			(end 0.94 -0.47)
			(stroke
				(width 0.05)
				(type solid)
			)
			(fill no)
			(layer "B.CrtYd")
		)
		(fp_rect
			(start -0.499 0.249)
			(end 0.499 -0.249)
			(stroke
				(width 0.15)
				(type solid)
			)
			(fill no)
			(layer "B.Fab")
		)
		(pad "1" smd roundrect
			(at -0.484 0)
			(size 0.59 0.64)
			(layers "B.Cu" "B.Mask" "B.Paste")
			(roundrect_rratio 0.25)
			(net 459 "3V3_SYS")
			(pintype "passive")
		)
		(pad "2" smd roundrect
			(at 0.484 0)
			(size 0.59 0.64)
			(layers "B.Cu" "B.Mask" "B.Paste")
			(roundrect_rratio 0.25)
			(net 5 "GND")
			(pintype "passive")
		)
	)
	(footprint "antmicro-footprints:R_0805_2012Metric"
		(layer "B.Cu")
		(at 136.3 75.6)
		(property "Reference" "R164"
			(at -1.6 0.4 180)
			(layer "B.SilkS")
			(effects
				(font
					(size 0.7 0.7)
					(thickness 0.15)
				)
				(justify left bottom mirror)
			)
		)
		(property "Value" "R_0R_0805"
			(at 0 -1.8 180)
			(layer "B.Fab")
			(effects
				(font
					(size 0.7 0.7)
					(thickness 0.15)
				)
				(justify left bottom mirror)
			)
		)
		(property "Description" "0R resistor in 0805 package with unspecified tolerance"
			(at 0 0 0)
			(layer "F.Fab")
			(hide yes)
			(effects
				(font
					(size 1.27 1.27)
					(thickness 0.15)
				)
			)
		)
		(property "Author" "Antmicro"
			(at 0 0 0)
			(layer "B.Fab")
			(hide yes)
			(effects
				(font
					(size 1 1)
					(thickness 0.15)
				)
				(justify mirror)
			)
		)
		(property "Current" "2.5A"
			(at 0 0 0)
			(layer "B.Fab")
			(hide yes)
			(effects
				(font
					(size 1 1)
					(thickness 0.15)
				)
				(justify mirror)
			)
		)
		(property "License" "Apache-2.0"
			(at 0 0 0)
			(layer "B.Fab")
			(hide yes)
			(effects
				(font
					(size 1 1)
					(thickness 0.15)
				)
				(justify mirror)
			)
		)
		(property "MPN" "CRCW08050000Z0EA"
			(at 0 0 0)
			(layer "B.Fab")
			(hide yes)
			(effects
				(font
					(size 1 1)
					(thickness 0.15)
				)
				(justify mirror)
			)
		)
		(property "Manufacturer" "Vishay"
			(at 0 0 0)
			(layer "B.Fab")
			(hide yes)
			(effects
				(font
					(size 1 1)
					(thickness 0.15)
				)
				(justify mirror)
			)
		)
		(property "Tolerance" ""
			(at 0 0 0)
			(layer "B.Fab")
			(hide yes)
			(effects
				(font
					(size 1 1)
					(thickness 0.15)
				)
				(justify mirror)
			)
		)
		(property "Val" "0R"
			(at 0 0 0)
			(layer "B.Fab")
			(hide yes)
			(effects
				(font
					(size 1 1)
					(thickness 0.15)
				)
				(justify mirror)
			)
		)
		(sheetname "Supply")
		(sheetfile "supply.kicad_sch")
		(attr smd)
		(fp_line
			(start -0.32 -0.699)
			(end 0.28 -0.699)
			(stroke
				(width 0.15)
				(type solid)
			)
			(layer "B.SilkS")
		)
		(fp_line
			(start -0.3 0.701)
			(end 0.298 0.701)
			(stroke
				(width 0.15)
				(type solid)
			)
			(layer "B.SilkS")
		)
		(fp_rect
			(start -1.75 0.85)
			(end 1.75 -0.85)
			(stroke
				(width 0.05)
				(type solid)
			)
			(fill no)
			(layer "B.CrtYd")
		)
		(fp_line
			(start -0.951 -0.68)
			(end 0.949 -0.68)
			(stroke
				(width 0.15)
				(type solid)
			)
			(layer "B.Fab")
		)
		(fp_line
			(start -0.951 0.677)
			(end -0.951 -0.675)
			(stroke
				(width 0.15)
				(type solid)
			)
			(layer "B.Fab")
		)
		(fp_line
			(start -0.951 0.682)
			(end 0.949 0.682)
			(stroke
				(width 0.15)
				(type solid)
			)
			(layer "B.Fab")
		)
		(fp_line
			(start 0.949 0.677)
			(end 0.949 -0.675)
			(stroke
				(width 0.15)
				(type solid)
			)
			(layer "B.Fab")
		)
		(pad "1" smd roundrect
			(at -1.1 0.001)
			(size 1 1.4)
			(layers "B.Cu" "B.Mask" "B.Paste")
			(roundrect_rratio 0.15)
			(net 461 "1V1_SYS")
			(pintype "passive")
		)
		(pad "2" smd roundrect
			(at 1.1 0.001)
			(size 1 1.4)
			(layers "B.Cu" "B.Mask" "B.Paste")
			(roundrect_rratio 0.15)
			(net 273 "1V1_DDR")
			(pintype "passive")
		)
	)
	(footprint "antmicro-footprints:R_0402_1005Metric"
		(layer "B.Cu")
		(at 134.2 79.7 180)
		(descr "Resistor SMD 0402")
		(tags "resistor SMD 0402")
		(property "Reference" "R161"
			(at 0.7 -0.4 0)
			(layer "B.SilkS")
			(effects
				(font
					(size 0.7 0.7)
					(thickness 0.15)
				)
				(justify left bottom mirror)
			)
		)
		(property "Value" "R_10k_0402"
			(at 0 -1.4 0)
			(layer "B.Fab")
			(effects
				(font
					(size 0.7 0.7)
					(thickness 0.15)
				)
				(justify left bottom mirror)
			)
		)
		(property "Description" "10k resistor in 0402 package with 1% tolerance"
			(at 0 0 180)
			(layer "F.Fab")
			(hide yes)
			(effects
				(font
					(size 1.27 1.27)
					(thickness 0.15)
				)
			)
		)
		(property "Author" "Antmicro"
			(at 268.4 159.4 0)
			(layer "B.Fab")
			(hide yes)
			(effects
				(font
					(size 1 1)
					(thickness 0.15)
				)
				(justify mirror)
			)
		)
		(property "License" "Apache-2.0"
			(at 268.4 159.4 0)
			(layer "B.Fab")
			(hide yes)
			(effects
				(font
					(size 1 1)
					(thickness 0.15)
				)
				(justify mirror)
			)
		)
		(property "MPN" "CR0402-FX-1002GLF"
			(at 268.4 159.4 0)
			(layer "B.Fab")
			(hide yes)
			(effects
				(font
					(size 1 1)
					(thickness 0.15)
				)
				(justify mirror)
			)
		)
		(property "Manufacturer" "Bourns"
			(at 268.4 159.4 0)
			(layer "B.Fab")
			(hide yes)
			(effects
				(font
					(size 1 1)
					(thickness 0.15)
				)
				(justify mirror)
			)
		)
		(property "Tolerance" "1%"
			(at 268.4 159.4 0)
			(layer "B.Fab")
			(hide yes)
			(effects
				(font
					(size 1 1)
					(thickness 0.15)
				)
				(justify mirror)
			)
		)
		(property "Val" "10k"
			(at 268.4 159.4 0)
			(layer "B.Fab")
			(hide yes)
			(effects
				(font
					(size 1 1)
					(thickness 0.15)
				)
				(justify mirror)
			)
		)
		(sheetname "Supply")
		(sheetfile "supply.kicad_sch")
		(attr exclude_from_pos_files exclude_from_bom dnp)
		(fp_rect
			(start -0.93 0.47)
			(end 0.93 -0.47)
			(stroke
				(width 0.05)
				(type solid)
			)
			(fill no)
			(layer "B.CrtYd")
		)
		(fp_rect
			(start -0.5 0.25)
			(end 0.5 -0.25)
			(stroke
				(width 0.15)
				(type solid)
			)
			(fill no)
			(layer "B.Fab")
		)
		(pad "1" smd roundrect
			(at -0.485 0 180)
			(size 0.59 0.64)
			(layers "B.Cu" "B.Mask" "B.Paste")
			(roundrect_rratio 0.25)
			(net 459 "3V3_SYS")
			(pintype "passive")
		)
		(pad "2" smd roundrect
			(at 0.485 0 180)
			(size 0.59 0.64)
			(layers "B.Cu" "B.Mask" "B.Paste")
			(roundrect_rratio 0.25)
			(net 263 "Net-(U15-ON)")
			(pintype "passive")
		)
	)
)
